# T6G (Grand Teton) — schematic netlist excerpt (pin names and nets, part order shuffled) for the footprints in the layout excerpt that follows; sources: Cadence DE-HDL packaged netlist, KiCad conversion of 04192023_DAF0TMB3IC0_F0TG_MB_C_brd_V02_OCP.brd

PR4010  Q_RES  120K 1% CHIP  pkg 0402LF  page 152 : A = P12V_AUX ; B = P12V_SCM_OV_FB
R3293  Q_RES  4.7K 1% EMPTY  pkg 0402LF  page 111 : A = FM_P2E_MODE ; B = GND

(kicad_pcb
	(version 20260206)
	(generator "pcbnew")
	(generator_version "10.0")
	(general
		(thickness 1.6)
		(legacy_teardrops no)
	)
	(paper "A4")
	(title_block
		(title "04192023_DAF0TMB3IC0_F0TG_MB_C_brd_V02_OCP.brd")
		(comment 1 "Grand Teton / footprints 2639-2640 of 8354")
	)
	(layers
		(0 "F.Cu" signal "TOP")
		(4 "In1.Cu" signal "GND")
		(6 "In2.Cu" signal "IN1")
		(8 "In3.Cu" signal "GND1")
		(10 "In4.Cu" signal "IN2")
		(12 "In5.Cu" signal "GND2")
		(14 "In6.Cu" signal "IN3")
		(16 "In7.Cu" signal "GND3")
		(18 "In8.Cu" signal "VCC")
		(20 "In9.Cu" signal "VCC1")
		(22 "In10.Cu" signal "GND4")
		(24 "In11.Cu" signal "IN4")
		(26 "In12.Cu" signal "GND5")
		(28 "In13.Cu" signal "IN5")
		(30 "In14.Cu" signal "GND6")
		(32 "In15.Cu" signal "IN6")
		(34 "In16.Cu" signal "GND7")
		(2 "B.Cu" signal "BOTTOM")
		(9 "F.Adhes" user "F.Adhesive")
		(11 "B.Adhes" user "B.Adhesive")
		(13 "F.Paste" user "Package Geometry/Pastemask Top")
		(15 "B.Paste" user "Package Geometry/Pastemask Bottom")
		(5 "F.SilkS" user "Ref Des/Silkscreen Top")
		(7 "B.SilkS" user "Ref Des/Silkscreen Bottom")
		(1 "F.Mask" user "Board Geometry/Soldermask Top")
		(3 "B.Mask" user "Board Geometry/Soldermask Bottom")
		(17 "Dwgs.User" user "User.Drawings")
		(19 "Cmts.User" user "User.Comments")
		(21 "Eco1.User" user "User.Eco1")
		(23 "Eco2.User" user "User.Eco2")
		(25 "Edge.Cuts" user "Board Geometry/Outline")
		(27 "Margin" user)
		(31 "F.CrtYd" user "Package Geometry/Place Bound Top")
		(29 "B.CrtYd" user "Package Geometry/Place Bound Bottom")
		(35 "F.Fab" user "Ref Des/Assembly Top")
		(33 "B.Fab" user "Ref Des/Assembly Bottom")
	)
	(footprint ""
		(layer "F.Cu")
		(at 172.878242 -28.03779 90)
		(property "Reference" "PR4010"
			(at 0 0 90)
			(layer "F.SilkS")
			(hide yes)
			(effects
				(font
					(size 1.27 1.27)
				)
			)
		)
		(property "Value" ""
			(at 0 0 90)
			(layer "F.Fab")
			(effects
				(font
					(size 1.27 1.27)
				)
			)
		)
		(duplicate_pad_numbers_are_jumpers no)
		(fp_line
			(start 0.7874 -0.4064)
			(end 0.7874 0.4064)
			(stroke
				(width 0.1524)
				(type default)
			)
			(layer "F.SilkS")
		)
		(fp_line
			(start -0.7874 -0.4064)
			(end 0.7874 -0.4064)
			(stroke
				(width 0.1524)
				(type default)
			)
			(layer "F.SilkS")
		)
		(fp_line
			(start 0.7874 0.4064)
			(end -0.7874 0.4064)
			(stroke
				(width 0.1524)
				(type default)
			)
			(layer "F.SilkS")
		)
		(fp_line
			(start -0.7874 0.4064)
			(end -0.7874 -0.4064)
			(stroke
				(width 0.1524)
				(type default)
			)
			(layer "F.SilkS")
		)
		(fp_line
			(start -0.12065 -0.305054)
			(end -0.12065 -0.2794)
			(stroke
				(width 0.1)
				(type default)
			)
			(layer "F.Fab")
		)
		(fp_line
			(start -0.67945 -0.305054)
			(end -0.12065 -0.305054)
			(stroke
				(width 0.1)
				(type default)
			)
			(layer "F.Fab")
		)
		(fp_line
			(start 0.67945 -0.3048)
			(end 0.67945 0.3048)
			(stroke
				(width 0.1)
				(type default)
			)
			(layer "F.Fab")
		)
		(fp_line
			(start 0.12065 -0.3048)
			(end 0.67945 -0.3048)
			(stroke
				(width 0.1)
				(type default)
			)
			(layer "F.Fab")
		)
		(fp_line
			(start 0.12065 -0.2794)
			(end 0.12065 -0.3048)
			(stroke
				(width 0.1)
				(type default)
			)
			(layer "F.Fab")
		)
		(fp_line
			(start -0.12065 -0.2794)
			(end 0.12065 -0.2794)
			(stroke
				(width 0.1)
				(type default)
			)
			(layer "F.Fab")
		)
		(fp_line
			(start 0.120396 0.2794)
			(end -0.12065 0.2794)
			(stroke
				(width 0.1)
				(type default)
			)
			(layer "F.Fab")
		)
		(fp_line
			(start -0.12065 0.2794)
			(end -0.12065 0.3048)
			(stroke
				(width 0.1)
				(type default)
			)
			(layer "F.Fab")
		)
		(fp_line
			(start 0.67945 0.3048)
			(end 0.120396 0.3048)
			(stroke
				(width 0.1)
				(type default)
			)
			(layer "F.Fab")
		)
		(fp_line
			(start 0.120396 0.3048)
			(end 0.120396 0.2794)
			(stroke
				(width 0.1)
				(type default)
			)
			(layer "F.Fab")
		)
		(fp_line
			(start -0.12065 0.3048)
			(end -0.67945 0.3048)
			(stroke
				(width 0.1)
				(type default)
			)
			(layer "F.Fab")
		)
		(fp_line
			(start -0.67945 0.3048)
			(end -0.67945 -0.305054)
			(stroke
				(width 0.1)
				(type default)
			)
			(layer "F.Fab")
		)
		(pad "1" smd circle
			(at -0.40005 0 90)
			(size 0 0)
			(layers "F.Cu" "F.Mask" "F.Paste")
			(net "P12V_AUX")
		)
		(pad "2" smd circle
			(at 0.40005 0 90)
			(size 0 0)
			(layers "F.Cu" "F.Mask" "F.Paste")
			(net "P12V_SCM_OV_FB")
		)
	)
	(footprint ""
		(layer "F.Cu")
		(at 37.681662 -419.249098 -90)
		(property "Reference" "R3293"
			(at 0 0 270)
			(layer "F.SilkS")
			(hide yes)
			(effects
				(font
					(size 1.27 1.27)
				)
			)
		)
		(property "Value" ""
			(at 0 0 270)
			(layer "F.Fab")
			(effects
				(font
					(size 1.27 1.27)
				)
			)
		)
		(duplicate_pad_numbers_are_jumpers no)
		(fp_line
			(start -0.7874 0.4064)
			(end -0.7874 -0.4064)
			(stroke
				(width 0.1524)
				(type default)
			)
			(layer "F.SilkS")
		)
		(fp_line
			(start 0.7874 0.4064)
			(end -0.7874 0.4064)
			(stroke
				(width 0.1524)
				(type default)
			)
			(layer "F.SilkS")
		)
		(fp_line
			(start -0.7874 -0.4064)
			(end 0.7874 -0.4064)
			(stroke
				(width 0.1524)
				(type default)
			)
			(layer "F.SilkS")
		)
		(fp_line
			(start 0.7874 -0.4064)
			(end 0.7874 0.4064)
			(stroke
				(width 0.1524)
				(type default)
			)
			(layer "F.SilkS")
		)
		(fp_line
			(start -0.67945 0.3048)
			(end -0.67945 -0.305054)
			(stroke
				(width 0.1)
				(type default)
			)
			(layer "F.Fab")
		)
		(fp_line
			(start -0.12065 0.3048)
			(end -0.67945 0.3048)
			(stroke
				(width 0.1)
				(type default)
			)
			(layer "F.Fab")
		)
		(fp_line
			(start 0.120396 0.3048)
			(end 0.120396 0.2794)
			(stroke
				(width 0.1)
				(type default)
			)
			(layer "F.Fab")
		)
		(fp_line
			(start 0.67945 0.3048)
			(end 0.120396 0.3048)
			(stroke
				(width 0.1)
				(type default)
			)
			(layer "F.Fab")
		)
		(fp_line
			(start -0.12065 0.2794)
			(end -0.12065 0.3048)
			(stroke
				(width 0.1)
				(type default)
			)
			(layer "F.Fab")
		)
		(fp_line
			(start 0.120396 0.2794)
			(end -0.12065 0.2794)
			(stroke
				(width 0.1)
				(type default)
			)
			(layer "F.Fab")
		)
		(fp_line
			(start -0.12065 -0.2794)
			(end 0.12065 -0.2794)
			(stroke
				(width 0.1)
				(type default)
			)
			(layer "F.Fab")
		)
		(fp_line
			(start 0.12065 -0.2794)
			(end 0.12065 -0.3048)
			(stroke
				(width 0.1)
				(type default)
			)
			(layer "F.Fab")
		)
		(fp_line
			(start 0.12065 -0.3048)
			(end 0.67945 -0.3048)
			(stroke
				(width 0.1)
				(type default)
			)
			(layer "F.Fab")
		)
		(fp_line
			(start 0.67945 -0.3048)
			(end 0.67945 0.3048)
			(stroke
				(width 0.1)
				(type default)
			)
			(layer "F.Fab")
		)
		(fp_line
			(start -0.67945 -0.305054)
			(end -0.12065 -0.305054)
			(stroke
				(width 0.1)
				(type default)
			)
			(layer "F.Fab")
		)
		(fp_line
			(start -0.12065 -0.305054)
			(end -0.12065 -0.2794)
			(stroke
				(width 0.1)
				(type default)
			)
			(layer "F.Fab")
		)
		(pad "1" smd circle
			(at -0.40005 0 270)
			(size 0 0)
			(layers "F.Cu" "F.Mask" "F.Paste")
			(net "FM_P2E_MODE")
		)
		(pad "2" smd circle
			(at 0.40005 0 270)
			(size 0 0)
			(layers "F.Cu" "F.Mask" "F.Paste")
			(net "GND")
		)
	)
)
